(kicad_pcb
	(version 20260206)
	(generator "pcbnew")
	(generator_version "10.0")
	(general
		(thickness 1.6)
		(legacy_teardrops no)
	)
	(paper "A4")
	(title_block
		(title "01162023_DA0F0TEBIF0_F0T_Expander_BD_F_brd_V02_OCP.brd")
		(comment 1 "Grand Teton / footprints 4498-4499 of 9728")
	)
	(layers
		(0 "F.Cu" signal "TOP")
		(4 "In1.Cu" signal "GND")
		(6 "In2.Cu" signal "VCC")
		(8 "In3.Cu" signal "VCC1")
		(10 "In4.Cu" signal "GND1")
		(12 "In5.Cu" signal "IN1")
		(14 "In6.Cu" signal "GND2")
		(16 "In7.Cu" signal "IN2")
		(18 "In8.Cu" signal "GND3")
		(20 "In9.Cu" signal "IN3")
		(22 "In10.Cu" signal "GND4")
		(24 "In11.Cu" signal "IN4")
		(26 "In12.Cu" signal "GND5")
		(28 "In13.Cu" signal "IN5")
		(30 "In14.Cu" signal "GND6")
		(32 "In15.Cu" signal "IN6")
		(34 "In16.Cu" signal "GND7")
		(2 "B.Cu" signal "BOTTOM")
		(9 "F.Adhes" user "F.Adhesive")
		(11 "B.Adhes" user "B.Adhesive")
		(13 "F.Paste" user "Package Geometry/Pastemask Top")
		(15 "B.Paste" user "Package Geometry/Pastemask Bottom")
		(5 "F.SilkS" user "Ref Des/Silkscreen Top")
		(7 "B.SilkS" user "Ref Des/Silkscreen Bottom")
		(1 "F.Mask" user "Board Geometry/Soldermask Top")
		(3 "B.Mask" user "Board Geometry/Soldermask Bottom")
		(17 "Dwgs.User" user "User.Drawings")
		(19 "Cmts.User" user "User.Comments")
		(21 "Eco1.User" user "User.Eco1")
		(23 "Eco2.User" user "User.Eco2")
		(25 "Edge.Cuts" user "Board Geometry/Outline")
		(27 "Margin" user)
		(31 "F.CrtYd" user "Package Geometry/Place Bound Top")
		(29 "B.CrtYd" user "Package Geometry/Place Bound Bottom")
		(35 "F.Fab" user "Ref Des/Assembly Top")
		(33 "B.Fab" user "Ref Des/Assembly Bottom")
	)
	(footprint ""
		(layer "F.Cu")
		(at 224.022158 -80.611472 180)
		(property "Reference" "R4349"
			(at 0 0 180)
			(layer "F.SilkS")
			(hide yes)
			(effects
				(font
					(size 1.27 1.27)
				)
			)
		)
		(property "Value" ""
			(at 0 0 180)
			(layer "F.Fab")
			(effects
				(font
					(size 1.27 1.27)
				)
			)
		)
		(duplicate_pad_numbers_are_jumpers no)
		(fp_line
			(start 0.7874 0.4064)
			(end -0.7874 0.4064)
			(stroke
				(width 0.1524)
				(type default)
			)
			(layer "F.SilkS")
		)
		(fp_line
			(start 0.7874 -0.4064)
			(end 0.7874 0.4064)
			(stroke
				(width 0.1524)
				(type default)
			)
			(layer "F.SilkS")
		)
		(fp_line
			(start -0.7874 0.4064)
			(end -0.7874 -0.4064)
			(stroke
				(width 0.1524)
				(type default)
			)
			(layer "F.SilkS")
		)
		(fp_line
			(start -0.7874 -0.4064)
			(end 0.7874 -0.4064)
			(stroke
				(width 0.1524)
				(type default)
			)
			(layer "F.SilkS")
		)
		(fp_line
			(start 0.67945 0.3048)
			(end 0.120396 0.3048)
			(stroke
				(width 0.1)
				(type default)
			)
			(layer "F.Fab")
		)
		(fp_line
			(start 0.67945 -0.3048)
			(end 0.67945 0.3048)
			(stroke
				(width 0.1)
				(type default)
			)
			(layer "F.Fab")
		)
		(fp_line
			(start 0.12065 -0.2794)
			(end 0.12065 -0.3048)
			(stroke
				(width 0.1)
				(type default)
			)
			(layer "F.Fab")
		)
		(fp_line
			(start 0.12065 -0.3048)
			(end 0.67945 -0.3048)
			(stroke
				(width 0.1)
				(type default)
			)
			(layer "F.Fab")
		)
		(fp_line
			(start 0.120396 0.3048)
			(end 0.120396 0.2794)
			(stroke
				(width 0.1)
				(type default)
			)
			(layer "F.Fab")
		)
		(fp_line
			(start 0.120396 0.2794)
			(end -0.12065 0.2794)
			(stroke
				(width 0.1)
				(type default)
			)
			(layer "F.Fab")
		)
		(fp_line
			(start -0.12065 0.3048)
			(end -0.67945 0.3048)
			(stroke
				(width 0.1)
				(type default)
			)
			(layer "F.Fab")
		)
		(fp_line
			(start -0.12065 0.2794)
			(end -0.12065 0.3048)
			(stroke
				(width 0.1)
				(type default)
			)
			(layer "F.Fab")
		)
		(fp_line
			(start -0.12065 -0.2794)
			(end 0.12065 -0.2794)
			(stroke
				(width 0.1)
				(type default)
			)
			(layer "F.Fab")
		)
		(fp_line
			(start -0.12065 -0.305054)
			(end -0.12065 -0.2794)
			(stroke
				(width 0.1)
				(type default)
			)
			(layer "F.Fab")
		)
		(fp_line
			(start -0.67945 0.3048)
			(end -0.67945 -0.305054)
			(stroke
				(width 0.1)
				(type default)
			)
			(layer "F.Fab")
		)
		(fp_line
			(start -0.67945 -0.305054)
			(end -0.12065 -0.305054)
			(stroke
				(width 0.1)
				(type default)
			)
			(layer "F.Fab")
		)
		(pad "1" smd circle
			(at -0.40005 0 180)
			(size 0 0)
			(layers "F.Cu" "F.Mask" "F.Paste")
			(net "P3V3_AUX")
		)
		(pad "2" smd circle
			(at 0.40005 0 180)
			(size 0 0)
			(layers "F.Cu" "F.Mask" "F.Paste")
			(net "SSD11_LED_R")
		)
	)
	(footprint ""
		(layer "F.Cu")
		(at 207.064864 -26.785062 180)
		(property "Reference" "J37"
			(at 4.53009 -10.920222 90)
			(unlocked yes)
			(layer "F.SilkS")
			(effects
				(font
					(size 0.7874 0.5842)
					(thickness 0.1524)
				)
			)
		)
		(property "Value" ""
			(at 0 0 180)
			(layer "F.Fab")
			(effects
				(font
					(size 1.27 1.27)
				)
			)
		)
		(duplicate_pad_numbers_are_jumpers no)
		(fp_line
			(start 3.150108 12.115038)
			(end 1.529334 12.115038)
			(stroke
				(width 0.1524)
				(type default)
			)
			(layer "F.SilkS")
		)
		(fp_line
			(start 3.074924 12.014962)
			(end 1.632204 12.014962)
			(stroke
				(width 0.1524)
				(type default)
			)
			(layer "F.SilkS")
		)
		(fp_line
			(start 1.632204 -12.014962)
			(end 3.074924 -12.014962)
			(stroke
				(width 0.1524)
				(type default)
			)
			(layer "F.SilkS")
		)
		(fp_line
			(start 1.529334 -12.115038)
			(end 3.150108 -12.115038)
			(stroke
				(width 0.1524)
				(type default)
			)
			(layer "F.SilkS")
		)
		(fp_line
			(start -1.529334 12.115038)
			(end -3.150108 12.115038)
			(stroke
				(width 0.1524)
				(type default)
			)
			(layer "F.SilkS")
		)
		(fp_line
			(start -1.632204 12.014962)
			(end -3.074924 12.014962)
			(stroke
				(width 0.1524)
				(type default)
			)
			(layer "F.SilkS")
		)
		(fp_line
			(start -3.074924 -12.014962)
			(end -1.632204 -12.014962)
			(stroke
				(width 0.1524)
				(type default)
			)
			(layer "F.SilkS")
		)
		(fp_line
			(start -3.150108 -12.115038)
			(end -1.529334 -12.115038)
			(stroke
				(width 0.1524)
				(type default)
			)
			(layer "F.SilkS")
		)
		(fp_poly
			(pts
				(xy 3.446526 -8.951214) (xy 3.868928 -10.218928) (xy 4.713986 -9.37387)
			)
			(stroke
				(width 0)
				(type default)
			)
			(fill yes)
			(layer "F.SilkS")
		)
		(fp_line
			(start 3.074924 12.014962)
			(end -3.074924 12.014962)
			(stroke
				(width 0.1)
				(type default)
			)
			(layer "F.Fab")
		)
		(fp_line
			(start 3.074924 -12.014962)
			(end 3.074924 12.014962)
			(stroke
				(width 0.1)
				(type default)
			)
			(layer "F.Fab")
		)
		(fp_line
			(start -3.074924 12.014962)
			(end -3.074924 -12.014962)
			(stroke
				(width 0.1)
				(type default)
			)
			(layer "F.Fab")
		)
		(fp_line
			(start -3.074924 -12.014962)
			(end 3.074924 -12.014962)
			(stroke
				(width 0.1)
				(type default)
			)
			(layer "F.Fab")
		)
		(fp_poly
			(pts
				(xy 3.348736 -7.994904) (xy 4.543806 -8.592566) (xy 4.543806 -7.397496)
			)
			(stroke
				(width 0)
				(type default)
			)
			(fill yes)
			(layer "F.Fab")
		)
		(pad "" np_thru_hole circle
			(at -1.75006 -9.815068 90)
			(size 1.1176 1.1176)
			(drill 1.1176)
			(layers "*.Cu" "*.Mask")
			(clearance 0.381)
			(thermal_gap 0.381)
		)
		(pad "" np_thru_hole circle
			(at 0 9.815068 90)
			(size 1.1176 1.1176)
			(drill 1.1176)
			(layers "*.Cu" "*.Mask")
			(clearance 0.381)
			(thermal_gap 0.381)
		)
		(pad "A1" smd rect
			(at 2.29997 -7.994904 90)
			(size 0.381 1.27)
			(layers "F.Cu" "F.Mask" "F.Paste")
			(net "GND")
		)
		(pad "A2" smd rect
			(at 2.29997 -7.394956 90)
			(size 0.381 1.27)
			(layers "F.Cu" "F.Mask" "F.Paste")
			(net "GND")
		)
		(pad "A3" smd rect
			(at 2.29997 -6.795008 90)
			(size 0.381 1.27)
			(layers "F.Cu" "F.Mask" "F.Paste")
			(net "GND")
		)
		(pad "A4" smd rect
			(at 2.29997 -6.19506 90)
			(size 0.381 1.27)
			(layers "F.Cu" "F.Mask" "F.Paste")
			(net "GND")
		)
		(pad "A5" smd rect
			(at 2.29997 -5.595112 90)
			(size 0.381 1.27)
			(layers "F.Cu" "F.Mask" "F.Paste")
			(net "GND")
		)
		(pad "A6" smd rect
			(at 2.29997 -4.99491 90)
			(size 0.381 1.27)
			(layers "F.Cu" "F.Mask" "F.Paste")
			(net "GND")
		)
		(pad "A7" smd rect
			(at 2.29997 -4.394962 90)
			(size 0.381 1.27)
			(layers "F.Cu" "F.Mask" "F.Paste")
			(net "SMB_ISO_SSD7_R_SCL")
		)
		(pad "A8" smd rect
			(at 2.29997 -3.795014 90)
			(size 0.381 1.27)
			(layers "F.Cu" "F.Mask" "F.Paste")
			(net "SMB_ISO_SSD7_R_SDA")
		)
		(pad "A9" smd rect
			(at 2.29997 -3.195066 90)
			(size 0.381 1.27)
			(layers "F.Cu" "F.Mask" "F.Paste")
			(net "RST_SMB_SSD7_ISO_R_N")
		)
		(pad "A10" smd rect
			(at 2.29997 -2.595118 90)
			(size 0.381 1.27)
			(layers "F.Cu" "F.Mask" "F.Paste")
			(net "SSD7_LED_ISO_R_N")
		)
		(pad "A11" smd rect
			(at 2.29997 -1.994916 90)
			(size 0.381 1.27)
			(layers "F.Cu" "F.Mask" "F.Paste")
			(net "PU_CLKREQ7")
		)
		(pad "A12" smd rect
			(at 2.29997 -1.394968 90)
			(size 0.381 1.27)
			(layers "F.Cu" "F.Mask" "F.Paste")
			(net "PRSNT_SSD7_N")
		)
		(pad "A13" smd rect
			(at 2.29997 -0.79502 90)
			(size 0.381 1.27)
			(layers "F.Cu" "F.Mask" "F.Paste")
			(net "GND")
		)
		(pad "A14" smd rect
			(at 2.29997 -0.195072 90)
			(size 0.381 1.27)
			(layers "F.Cu" "F.Mask" "F.Paste")
			(net "Net_8507")
		)
		(pad "A15" smd rect
			(at 2.29997 0.404876 90)
			(size 0.381 1.27)
			(layers "F.Cu" "F.Mask" "F.Paste")
			(net "Net_8506")
		)
		(pad "A16" smd rect
			(at 2.29997 1.005078 90)
			(size 0.381 1.27)
			(layers "F.Cu" "F.Mask" "F.Paste")
			(net "GND")
		)
		(pad "A17" smd rect
			(at 2.29997 1.605026 90)
			(size 0.381 1.27)
			(layers "F.Cu" "F.Mask" "F.Paste")
			(net "P5E_PEX1_STN2_RX_DN<32>")
		)
		(pad "A18" smd rect
			(at 2.29997 2.204974 90)
			(size 0.381 1.27)
			(layers "F.Cu" "F.Mask" "F.Paste")
			(net "P5E_PEX1_STN2_RX_DP<32>")
		)
		(pad "A19" smd rect
			(at 2.29997 2.804922 90)
			(size 0.381 1.27)
			(layers "F.Cu" "F.Mask" "F.Paste")
			(net "GND")
		)
		(pad "A20" smd rect
			(at 2.29997 3.405124 90)
			(size 0.381 1.27)
			(layers "F.Cu" "F.Mask" "F.Paste")
			(net "P5E_PEX1_STN2_RX_DN<33>")
		)
		(pad "A21" smd rect
			(at 2.29997 4.005072 90)
			(size 0.381 1.27)
			(layers "F.Cu" "F.Mask" "F.Paste")
			(net "P5E_PEX1_STN2_RX_DP<33>")
		)
		(pad "A22" smd rect
			(at 2.29997 4.60502 90)
			(size 0.381 1.27)
			(layers "F.Cu" "F.Mask" "F.Paste")
			(net "GND")
		)
		(pad "A23" smd rect
			(at 2.29997 5.204968 90)
			(size 0.381 1.27)
			(layers "F.Cu" "F.Mask" "F.Paste")
			(net "P5E_PEX1_STN2_RX_DN<34>")
		)
		(pad "A24" smd rect
			(at 2.29997 5.804916 90)
			(size 0.381 1.27)
			(layers "F.Cu" "F.Mask" "F.Paste")
			(net "P5E_PEX1_STN2_RX_DP<34>")
		)
		(pad "A25" smd rect
			(at 2.29997 6.405118 90)
			(size 0.381 1.27)
			(layers "F.Cu" "F.Mask" "F.Paste")
			(net "GND")
		)
		(pad "A26" smd rect
			(at 2.29997 7.005066 90)
			(size 0.381 1.27)
			(layers "F.Cu" "F.Mask" "F.Paste")
			(net "P5E_PEX1_STN2_RX_DN<35>")
		)
		(pad "A27" smd rect
			(at 2.29997 7.605014 90)
			(size 0.381 1.27)
			(layers "F.Cu" "F.Mask" "F.Paste")
			(net "P5E_PEX1_STN2_RX_DP<35>")
		)
		(pad "A28" smd rect
			(at 2.29997 8.204962 90)
			(size 0.381 1.27)
			(layers "F.Cu" "F.Mask" "F.Paste")
			(net "GND")
		)
		(pad "B1" smd rect
			(at -2.29997 -7.994904 90)
			(size 0.381 1.27)
			(layers "F.Cu" "F.Mask" "F.Paste")
			(net "P12V_SSD7")
		)
		(pad "B2" smd rect
			(at -2.29997 -7.394956 90)
			(size 0.381 1.27)
			(layers "F.Cu" "F.Mask" "F.Paste")
			(net "P12V_SSD7")
		)
		(pad "B3" smd rect
			(at -2.29997 -6.795008 90)
			(size 0.381 1.27)
			(layers "F.Cu" "F.Mask" "F.Paste")
			(net "P12V_SSD7")
		)
		(pad "B4" smd rect
			(at -2.29997 -6.19506 90)
			(size 0.381 1.27)
			(layers "F.Cu" "F.Mask" "F.Paste")
			(net "P12V_SSD7")
		)
		(pad "B5" smd rect
			(at -2.29997 -5.595112 90)
			(size 0.381 1.27)
			(layers "F.Cu" "F.Mask" "F.Paste")
			(net "P12V_SSD7")
		)
		(pad "B6" smd rect
			(at -2.29997 -4.99491 90)
			(size 0.381 1.27)
			(layers "F.Cu" "F.Mask" "F.Paste")
			(net "P12V_SSD7")
		)
		(pad "B7" smd rect
			(at -2.29997 -4.394962 90)
			(size 0.381 1.27)
			(layers "F.Cu" "F.Mask" "F.Paste")
			(net "Net_8508")
		)
		(pad "B8" smd rect
			(at -2.29997 -3.795014 90)
			(size 0.381 1.27)
			(layers "F.Cu" "F.Mask" "F.Paste")
			(net "Net_8505")
		)
		(pad "B9" smd rect
			(at -2.29997 -3.195066 90)
			(size 0.381 1.27)
			(layers "F.Cu" "F.Mask" "F.Paste")
			(net "DUALPORT_N_SSD7")
		)
		(pad "B10" smd rect
			(at -2.29997 -2.595118 90)
			(size 0.381 1.27)
			(layers "F.Cu" "F.Mask" "F.Paste")
			(net "RST_SSD7_PERST_R_N")
		)
		(pad "B11" smd rect
			(at -2.29997 -1.994916 90)
			(size 0.381 1.27)
			(layers "F.Cu" "F.Mask" "F.Paste")
			(net "P3V3_SSD7")
		)
		(pad "B12" smd rect
			(at -2.29997 -1.394968 90)
			(size 0.381 1.27)
			(layers "F.Cu" "F.Mask" "F.Paste")
			(net "SSD7_PWRDIS_R")
		)
		(pad "B13" smd rect
			(at -2.29997 -0.79502 90)
			(size 0.381 1.27)
			(layers "F.Cu" "F.Mask" "F.Paste")
			(net "GND")
		)
		(pad "B14" smd rect
			(at -2.29997 -0.195072 90)
			(size 0.381 1.27)
			(layers "F.Cu" "F.Mask" "F.Paste")
			(net "CLK_100M_DB800ZL_SSD7_R_DN")
		)
		(pad "B15" smd rect
			(at -2.29997 0.404876 90)
			(size 0.381 1.27)
			(layers "F.Cu" "F.Mask" "F.Paste")
			(net "CLK_100M_DB800ZL_SSD7_R_DP")
		)
		(pad "B16" smd rect
			(at -2.29997 1.005078 90)
			(size 0.381 1.27)
			(layers "F.Cu" "F.Mask" "F.Paste")
			(net "GND")
		)
		(pad "B17" smd rect
			(at -2.29997 1.605026 90)
			(size 0.381 1.27)
			(layers "F.Cu" "F.Mask" "F.Paste")
			(net "P5E_PEX1_STN2_TX_C_DN<32>")
		)
		(pad "B18" smd rect
			(at -2.29997 2.204974 90)
			(size 0.381 1.27)
			(layers "F.Cu" "F.Mask" "F.Paste")
			(net "P5E_PEX1_STN2_TX_C_DP<32>")
		)
		(pad "B19" smd rect
			(at -2.29997 2.804922 90)
			(size 0.381 1.27)
			(layers "F.Cu" "F.Mask" "F.Paste")
			(net "GND")
		)
		(pad "B20" smd rect
			(at -2.29997 3.405124 90)
			(size 0.381 1.27)
			(layers "F.Cu" "F.Mask" "F.Paste")
			(net "P5E_PEX1_STN2_TX_C_DN<33>")
		)
		(pad "B21" smd rect
			(at -2.29997 4.005072 90)
			(size 0.381 1.27)
			(layers "F.Cu" "F.Mask" "F.Paste")
			(net "P5E_PEX1_STN2_TX_C_DP<33>")
		)
		(pad "B22" smd rect
			(at -2.29997 4.60502 90)
			(size 0.381 1.27)
			(layers "F.Cu" "F.Mask" "F.Paste")
			(net "GND")
		)
		(pad "B23" smd rect
			(at -2.29997 5.204968 90)
			(size 0.381 1.27)
			(layers "F.Cu" "F.Mask" "F.Paste")
			(net "P5E_PEX1_STN2_TX_C_DN<34>")
		)
		(pad "B24" smd rect
			(at -2.29997 5.804916 90)
			(size 0.381 1.27)
			(layers "F.Cu" "F.Mask" "F.Paste")
			(net "P5E_PEX1_STN2_TX_C_DP<34>")
		)
		(pad "B25" smd rect
			(at -2.29997 6.405118 90)
			(size 0.381 1.27)
			(layers "F.Cu" "F.Mask" "F.Paste")
			(net "GND")
		)
		(pad "B26" smd rect
			(at -2.29997 7.005066 90)
			(size 0.381 1.27)
			(layers "F.Cu" "F.Mask" "F.Paste")
			(net "P5E_PEX1_STN2_TX_C_DN<35>")
		)
		(pad "B27" smd rect
			(at -2.29997 7.605014 90)
			(size 0.381 1.27)
			(layers "F.Cu" "F.Mask" "F.Paste")
			(net "P5E_PEX1_STN2_TX_C_DP<35>")
		)
		(pad "B28" smd rect
			(at -2.29997 8.204962 90)
			(size 0.381 1.27)
			(layers "F.Cu" "F.Mask" "F.Paste")
			(net "GND")
		)
		(pad "G1" thru_hole oval
			(at 0 -11.364976 90)
			(size 1.6256 3.4798)
			(drill oval 1.1176 2.4638)
			(layers "*.Cu" "*.Mask")
			(remove_unused_layers no)
			(net "GND")
			(clearance 0.127)
			(thermal_gap 0.127)
		)
		(pad "G2" thru_hole oval
			(at 0 11.364976 90)
			(size 1.6256 3.4798)
			(drill oval 1.1176 2.4638)
			(layers "*.Cu" "*.Mask")
			(remove_unused_layers no)
			(net "GND")
			(clearance 0.127)
			(thermal_gap 0.127)
		)
		(zone
			(layer "F.Cu")
			(hatch none 0.5)
			(connect_pads
				(clearance 0)
			)
			(min_thickness 0.25)
			(keepout
				(tracks not_allowed)
				(vias allowed)
				(pads allowed)
				(copperpour not_allowed)
				(footprints allowed)
			)
			(placement
				(enabled no)
				(sheetname "")
			)
			(fill
				(thermal_gap 0.5)
				(thermal_bridge_width 0.5)
				(island_removal_mode 0)
			)
			(polygon
				(pts
					(xy 208.444846 -38.850062) (xy 205.694788 -38.850062) (xy 205.694788 -35.900106) (xy 208.444846 -35.900106)
				)
			)
		)
		(zone
			(layer "F.Cu")
			(hatch none 0.5)
			(connect_pads
				(clearance 0)
			)
			(min_thickness 0.25)
			(keepout
				(tracks not_allowed)
				(vias allowed)
				(pads allowed)
				(copperpour not_allowed)
				(footprints allowed)
			)
			(placement
				(enabled no)
				(sheetname "")
			)
			(fill
				(thermal_gap 0.5)
				(thermal_bridge_width 0.5)
				(island_removal_mode 0)
			)
			(polygon
				(pts
					(xy 209.514948 -17.670018) (xy 205.684882 -17.670018) (xy 205.684882 -14.720062) (xy 209.514948 -14.720062)
				)
			)
		)
		(zone
			(layers "F.Cu" "B.Cu" "In1.Cu" "In2.Cu" "In3.Cu" "In4.Cu" "In5.Cu" "In6.Cu"
				"In7.Cu" "In8.Cu" "In9.Cu" "In10.Cu" "In11.Cu" "In12.Cu" "In13.Cu" "In14.Cu"
				"In15.Cu" "In16.Cu"
			)
			(hatch none 0.5)
			(connect_pads
				(clearance 0)
			)
			(min_thickness 0.25)
			(keepout
				(tracks not_allowed)
				(vias allowed)
				(pads allowed)
				(copperpour not_allowed)
				(footprints allowed)
			)
			(placement
				(enabled no)
				(sheetname "")
			)
			(fill
				(thermal_gap 0.5)
				(thermal_bridge_width 0.5)
				(island_removal_mode 0)
			)
			(polygon
				(pts
					(arc
						(start 208.030064 -36.60013)
						(mid 206.099664 -36.60013)
						(end 208.030064 -36.60013)
					)
				)
			)
		)
		(zone
			(layers "F.Cu" "B.Cu" "In1.Cu" "In2.Cu" "In3.Cu" "In4.Cu" "In5.Cu" "In6.Cu"
				"In7.Cu" "In8.Cu" "In9.Cu" "In10.Cu" "In11.Cu" "In12.Cu" "In13.Cu" "In14.Cu"
				"In15.Cu" "In16.Cu"
			)
			(hatch none 0.5)
			(connect_pads
				(clearance 0)
			)
			(min_thickness 0.25)
			(keepout
				(tracks not_allowed)
				(vias allowed)
				(pads allowed)
				(copperpour not_allowed)
				(footprints allowed)
			)
			(placement
				(enabled no)
				(sheetname "")
			)
			(fill
				(thermal_gap 0.5)
				(thermal_bridge_width 0.5)
				(island_removal_mode 0)
			)
			(polygon
				(pts
					(arc
						(start 209.780124 -16.969994)
						(mid 207.849724 -16.969994)
						(end 209.780124 -16.969994)
					)
				)
			)
		)
	)
)
